(kicad_pcb
	(version 20260206)
	(generator "pcbnew")
	(generator_version "10.0")
	(general
		(thickness 1.6)
		(legacy_teardrops no)
	)
	(paper "A4")
	(title_block
		(title "baseboard — 13948-1b.1110WZS1818.brd")
		(comment 1 "Honey Badger (Wiwynn) / footprints 288-294 of 2523")
	)
	(layers
		(0 "F.Cu" signal "TOP")
		(4 "In1.Cu" signal "L2GND")
		(6 "In2.Cu" signal "L3")
		(8 "In3.Cu" signal "L4VCC")
		(10 "In4.Cu" signal "L5VCC")
		(12 "In5.Cu" signal "L6")
		(14 "In6.Cu" signal "L7GND")
		(2 "B.Cu" signal "BOTTOM")
		(9 "F.Adhes" user "F.Adhesive")
		(11 "B.Adhes" user "B.Adhesive")
		(13 "F.Paste" user "Package Geometry/Pastemask Top")
		(15 "B.Paste" user "Package Geometry/Pastemask Bottom")
		(5 "F.SilkS" user "Ref Des/Silkscreen Top")
		(7 "B.SilkS" user "Ref Des/Silkscreen Bottom")
		(1 "F.Mask" user "Board Geometry/Soldermask Top")
		(3 "B.Mask" user "Board Geometry/Soldermask Bottom")
		(17 "Dwgs.User" user "User.Drawings")
		(19 "Cmts.User" user "User.Comments")
		(21 "Eco1.User" user "User.Eco1")
		(23 "Eco2.User" user "User.Eco2")
		(25 "Edge.Cuts" user "Board Geometry/Outline")
		(27 "Margin" user)
		(31 "F.CrtYd" user "Package Geometry/Place Bound Top")
		(29 "B.CrtYd" user "Package Geometry/Place Bound Bottom")
		(35 "F.Fab" user "Ref Des/Assembly Top")
		(33 "B.Fab" user "Ref Des/Assembly Bottom")
	)
	(footprint ""
		(layer "F.Cu")
		(at 271.272 -170.942 90)
		(property "Reference" "R269"
			(at 0 0 90)
			(layer "F.SilkS")
			(hide yes)
			(effects
				(font
					(size 1.27 1.27)
				)
			)
		)
		(property "Value" "10KR2F-2-GP"
			(at 0.064008 -3.993896 90)
			(unlocked yes)
			(layer "F.Fab")
			(hide yes)
			(effects
				(font
					(size 1.016 1.016)
					(thickness 0.1524)
				)
			)
		)
		(property "Device Type" "R402H16"
			(at 0.064008 -5.517896 90)
			(unlocked yes)
			(layer "F.Fab")
			(hide yes)
			(effects
				(font
					(size 1.016 1.016)
					(thickness 0.1524)
				)
			)
		)
		(duplicate_pad_numbers_are_jumpers no)
		(fp_line
			(start 0.508 -0.9398)
			(end -0.508 -0.9398)
			(stroke
				(width 0.1524)
				(type default)
			)
			(layer "F.SilkS")
		)
		(fp_line
			(start -0.508 -0.9398)
			(end -0.508 0.9398)
			(stroke
				(width 0.1524)
				(type default)
			)
			(layer "F.SilkS")
		)
		(fp_rect
			(start -0.508 0.9398)
			(end 0.508 -0.9398)
			(stroke
				(width 0)
				(type default)
			)
			(fill no)
			(layer "F.CrtYd")
		)
		(fp_rect
			(start -0.508 0.9398)
			(end 0.508 -0.9398)
			(stroke
				(width 0)
				(type default)
			)
			(fill no)
			(layer "F.Fab")
		)
		(pad "1" smd custom
			(at 0 -0.4445 90)
			(size 0.1397 0.1397)
			(layers "F.Cu" "F.Mask" "F.Paste")
			(net "P3V3_STBY")
			(options
				(clearance outline)
				(anchor circle)
			)
			(primitives
				(gr_poly
					(pts
						(arc
							(start -0.1778 -0.2794)
							(mid -0.249642 -0.249642)
							(end -0.2794 -0.1778)
						)
						(arc
							(start -0.2794 0.1778)
							(mid -0.249642 0.249642)
							(end -0.1778 0.2794)
						)
						(arc
							(start 0.1778 0.2794)
							(mid 0.249642 0.249642)
							(end 0.2794 0.1778)
						)
						(arc
							(start 0.2794 -0.1778)
							(mid 0.249642 -0.249642)
							(end 0.1778 -0.2794)
						)
					)
					(width 0)
					(fill yes)
				)
			)
		)
		(pad "2" smd custom
			(at 0 0.4445 90)
			(size 0.1397 0.1397)
			(layers "F.Cu" "F.Mask" "F.Paste")
			(net "BMC_MBC_I2C_E_SCL")
			(options
				(clearance outline)
				(anchor circle)
			)
			(primitives
				(gr_poly
					(pts
						(arc
							(start -0.1778 -0.2794)
							(mid -0.249642 -0.249642)
							(end -0.2794 -0.1778)
						)
						(arc
							(start -0.2794 0.1778)
							(mid -0.249642 0.249642)
							(end -0.1778 0.2794)
						)
						(arc
							(start 0.1778 0.2794)
							(mid 0.249642 0.249642)
							(end 0.2794 0.1778)
						)
						(arc
							(start 0.2794 -0.1778)
							(mid 0.249642 -0.249642)
							(end 0.1778 -0.2794)
						)
					)
					(width 0)
					(fill yes)
				)
			)
		)
	)
	(footprint ""
		(layer "F.Cu")
		(at 21.667216 -225.09988 180)
		(property "Reference" "SC429"
			(at 0 0 180)
			(layer "F.SilkS")
			(hide yes)
			(effects
				(font
					(size 1.27 1.27)
				)
			)
		)
		(property "Value" "SCD1U16V2KX-3GP"
			(at 1.1811 -2.7051 180)
			(unlocked yes)
			(layer "F.Fab")
			(hide yes)
			(effects
				(font
					(size 1.016 1.016)
					(thickness 0.1524)
				)
			)
		)
		(property "Device Type" "C402H22"
			(at 1.1811 -4.2291 180)
			(unlocked yes)
			(layer "F.Fab")
			(hide yes)
			(effects
				(font
					(size 1.016 1.016)
					(thickness 0.1524)
				)
			)
		)
		(duplicate_pad_numbers_are_jumpers no)
		(fp_rect
			(start -0.4318 0.9525)
			(end 0.4318 -0.9525)
			(stroke
				(width 0)
				(type default)
			)
			(fill no)
			(layer "F.CrtYd")
		)
		(fp_rect
			(start -0.4318 0.9525)
			(end 0.4318 -0.9525)
			(stroke
				(width 0)
				(type default)
			)
			(fill no)
			(layer "F.Fab")
		)
		(pad "1" smd custom
			(at 0 -0.4445 180)
			(size 0.1524 0.1524)
			(layers "F.Cu" "F.Mask" "F.Paste")
			(net "P3V3_STBY")
			(options
				(clearance outline)
				(anchor circle)
			)
			(primitives
				(gr_poly
					(pts
						(arc
							(start 0.3048 -0.2032)
							(mid 0.275042 -0.275042)
							(end 0.2032 -0.3048)
						)
						(arc
							(start -0.2032 -0.3048)
							(mid -0.275042 -0.275042)
							(end -0.3048 -0.2032)
						)
						(arc
							(start -0.3048 0.2032)
							(mid -0.275042 0.275042)
							(end -0.2032 0.3048)
						)
						(arc
							(start 0.2032 0.3048)
							(mid 0.275042 0.275042)
							(end 0.3048 0.2032)
						)
					)
					(width 0)
					(fill yes)
				)
			)
		)
		(pad "2" smd custom
			(at 0 0.4445 180)
			(size 0.1524 0.1524)
			(layers "F.Cu" "F.Mask" "F.Paste")
			(net "GND")
			(options
				(clearance outline)
				(anchor circle)
			)
			(primitives
				(gr_poly
					(pts
						(arc
							(start 0.3048 -0.2032)
							(mid 0.275042 -0.275042)
							(end 0.2032 -0.3048)
						)
						(arc
							(start -0.2032 -0.3048)
							(mid -0.275042 -0.275042)
							(end -0.3048 -0.2032)
						)
						(arc
							(start -0.3048 0.2032)
							(mid -0.275042 0.275042)
							(end -0.2032 0.3048)
						)
						(arc
							(start 0.2032 0.3048)
							(mid 0.275042 0.275042)
							(end 0.3048 0.2032)
						)
					)
					(width 0)
					(fill yes)
				)
			)
		)
	)
	(footprint ""
		(layer "F.Cu")
		(at 95.25 -69.342 180)
		(property "Reference" "SC968"
			(at 0 0 180)
			(layer "F.SilkS")
			(hide yes)
			(effects
				(font
					(size 1.27 1.27)
				)
			)
		)
		(property "Value" "SC1U10V2KX-4-GP"
			(at 1.1811 -2.7051 180)
			(unlocked yes)
			(layer "F.Fab")
			(hide yes)
			(effects
				(font
					(size 1.016 1.016)
					(thickness 0.1524)
				)
			)
		)
		(property "Device Type" "C402H22"
			(at 1.1811 -4.2291 180)
			(unlocked yes)
			(layer "F.Fab")
			(hide yes)
			(effects
				(font
					(size 1.016 1.016)
					(thickness 0.1524)
				)
			)
		)
		(duplicate_pad_numbers_are_jumpers no)
		(fp_rect
			(start -0.4318 0.9525)
			(end 0.4318 -0.9525)
			(stroke
				(width 0)
				(type default)
			)
			(fill no)
			(layer "F.CrtYd")
		)
		(fp_rect
			(start -0.4318 0.9525)
			(end 0.4318 -0.9525)
			(stroke
				(width 0)
				(type default)
			)
			(fill no)
			(layer "F.Fab")
		)
		(pad "1" smd custom
			(at 0 -0.4445 180)
			(size 0.1524 0.1524)
			(layers "F.Cu" "F.Mask" "F.Paste")
			(net "P1V8_C")
			(options
				(clearance outline)
				(anchor circle)
			)
			(primitives
				(gr_poly
					(pts
						(arc
							(start 0.3048 -0.2032)
							(mid 0.275042 -0.275042)
							(end 0.2032 -0.3048)
						)
						(arc
							(start -0.2032 -0.3048)
							(mid -0.275042 -0.275042)
							(end -0.3048 -0.2032)
						)
						(arc
							(start -0.3048 0.2032)
							(mid -0.275042 0.275042)
							(end -0.2032 0.3048)
						)
						(arc
							(start 0.2032 0.3048)
							(mid 0.275042 0.275042)
							(end 0.3048 0.2032)
						)
					)
					(width 0)
					(fill yes)
				)
			)
		)
		(pad "2" smd custom
			(at 0 0.4445 180)
			(size 0.1524 0.1524)
			(layers "F.Cu" "F.Mask" "F.Paste")
			(net "GND")
			(options
				(clearance outline)
				(anchor circle)
			)
			(primitives
				(gr_poly
					(pts
						(arc
							(start 0.3048 -0.2032)
							(mid 0.275042 -0.275042)
							(end 0.2032 -0.3048)
						)
						(arc
							(start -0.2032 -0.3048)
							(mid -0.275042 -0.275042)
							(end -0.3048 -0.2032)
						)
						(arc
							(start -0.3048 0.2032)
							(mid -0.275042 0.275042)
							(end -0.2032 0.3048)
						)
						(arc
							(start 0.2032 0.3048)
							(mid 0.275042 0.275042)
							(end 0.3048 0.2032)
						)
					)
					(width 0)
					(fill yes)
				)
			)
		)
	)
	(footprint ""
		(layer "F.Cu")
		(at 221.361 -105.156 -90)
		(property "Reference" "PR124"
			(at 0 0 270)
			(layer "F.SilkS")
			(hide yes)
			(effects
				(font
					(size 1.27 1.27)
				)
			)
		)
		(property "Value" "0R2J-2-GP"
			(at 0.064008 -3.993896 270)
			(unlocked yes)
			(layer "F.Fab")
			(hide yes)
			(effects
				(font
					(size 1.016 1.016)
					(thickness 0.1524)
				)
			)
		)
		(property "Device Type" "R402H16"
			(at 0.064008 -5.517896 270)
			(unlocked yes)
			(layer "F.Fab")
			(hide yes)
			(effects
				(font
					(size 1.016 1.016)
					(thickness 0.1524)
				)
			)
		)
		(duplicate_pad_numbers_are_jumpers no)
		(fp_line
			(start -0.508 -0.9398)
			(end -0.508 0.9398)
			(stroke
				(width 0.1524)
				(type default)
			)
			(layer "F.SilkS")
		)
		(fp_line
			(start 0.508 -0.9398)
			(end -0.508 -0.9398)
			(stroke
				(width 0.1524)
				(type default)
			)
			(layer "F.SilkS")
		)
		(fp_rect
			(start -0.508 0.9398)
			(end 0.508 -0.9398)
			(stroke
				(width 0)
				(type default)
			)
			(fill no)
			(layer "F.CrtYd")
		)
		(fp_rect
			(start -0.508 0.9398)
			(end 0.508 -0.9398)
			(stroke
				(width 0)
				(type default)
			)
			(fill no)
			(layer "F.Fab")
		)
		(pad "1" smd custom
			(at 0 -0.4445 270)
			(size 0.1397 0.1397)
			(layers "F.Cu" "F.Mask" "F.Paste")
			(net "P3V3_STBY")
			(options
				(clearance outline)
				(anchor circle)
			)
			(primitives
				(gr_poly
					(pts
						(arc
							(start -0.1778 -0.2794)
							(mid -0.249642 -0.249642)
							(end -0.2794 -0.1778)
						)
						(arc
							(start -0.2794 0.1778)
							(mid -0.249642 0.249642)
							(end -0.1778 0.2794)
						)
						(arc
							(start 0.1778 0.2794)
							(mid 0.249642 0.249642)
							(end 0.2794 0.1778)
						)
						(arc
							(start 0.2794 -0.1778)
							(mid 0.249642 -0.249642)
							(end 0.1778 -0.2794)
						)
					)
					(width 0)
					(fill yes)
				)
			)
		)
		(pad "2" smd custom
			(at 0 0.4445 270)
			(size 0.1397 0.1397)
			(layers "F.Cu" "F.Mask" "F.Paste")
			(net "TPS74801_1V5_C_BIAS")
			(options
				(clearance outline)
				(anchor circle)
			)
			(primitives
				(gr_poly
					(pts
						(arc
							(start -0.1778 -0.2794)
							(mid -0.249642 -0.249642)
							(end -0.2794 -0.1778)
						)
						(arc
							(start -0.2794 0.1778)
							(mid -0.249642 0.249642)
							(end -0.1778 0.2794)
						)
						(arc
							(start 0.1778 0.2794)
							(mid 0.249642 0.249642)
							(end 0.2794 0.1778)
						)
						(arc
							(start 0.2794 -0.1778)
							(mid 0.249642 -0.249642)
							(end 0.1778 -0.2794)
						)
					)
					(width 0)
					(fill yes)
				)
			)
		)
	)
	(footprint ""
		(layer "F.Cu")
		(at 346.075 -114.808 180)
		(property "Reference" "PC5"
			(at 0 0 180)
			(layer "F.SilkS")
			(hide yes)
			(effects
				(font
					(size 1.27 1.27)
				)
			)
		)
		(property "Value" "SC1U25V3KX-GP"
			(at 0 -2.8194 180)
			(unlocked yes)
			(layer "F.Fab")
			(hide yes)
			(effects
				(font
					(size 1.016 1.016)
					(thickness 0.1524)
				)
			)
		)
		(property "Device Type" "C603H36"
			(at 0 -4.3434 180)
			(unlocked yes)
			(layer "F.Fab")
			(hide yes)
			(effects
				(font
					(size 1.016 1.016)
					(thickness 0.1524)
				)
			)
		)
		(duplicate_pad_numbers_are_jumpers no)
		(fp_line
			(start 0.508 0)
			(end -0.508 0)
			(stroke
				(width 0.2032)
				(type default)
			)
			(layer "F.SilkS")
		)
		(fp_rect
			(start -0.5842 1.3335)
			(end 0.5842 -1.3335)
			(stroke
				(width 0)
				(type default)
			)
			(fill no)
			(layer "F.CrtYd")
		)
		(fp_rect
			(start -0.5842 1.3335)
			(end 0.5842 -1.3335)
			(stroke
				(width 0)
				(type default)
			)
			(fill no)
			(layer "F.Fab")
		)
		(pad "1" smd custom
			(at 0 -0.762 180)
			(size 0.2159 0.2159)
			(layers "F.Cu" "F.Mask" "F.Paste")
			(net "P5V_STBY_VCC")
			(options
				(clearance outline)
				(anchor circle)
			)
			(primitives
				(gr_poly
					(pts
						(arc
							(start -0.3302 -0.4318)
							(mid -0.402042 -0.402042)
							(end -0.4318 -0.3302)
						)
						(arc
							(start -0.4318 0.3302)
							(mid -0.402042 0.402042)
							(end -0.3302 0.4318)
						)
						(arc
							(start 0.3302 0.4318)
							(mid 0.402042 0.402042)
							(end 0.4318 0.3302)
						)
						(arc
							(start 0.4318 -0.3302)
							(mid 0.402042 -0.402042)
							(end 0.3302 -0.4318)
						)
					)
					(width 0)
					(fill yes)
				)
			)
		)
		(pad "2" smd custom
			(at 0 0.762 180)
			(size 0.2159 0.2159)
			(layers "F.Cu" "F.Mask" "F.Paste")
			(net "AGND_P5V_STBY")
			(options
				(clearance outline)
				(anchor circle)
			)
			(primitives
				(gr_poly
					(pts
						(arc
							(start -0.3302 -0.4318)
							(mid -0.402042 -0.402042)
							(end -0.4318 -0.3302)
						)
						(arc
							(start -0.4318 0.3302)
							(mid -0.402042 0.402042)
							(end -0.3302 0.4318)
						)
						(arc
							(start 0.3302 0.4318)
							(mid 0.402042 0.402042)
							(end 0.4318 0.3302)
						)
						(arc
							(start 0.4318 -0.3302)
							(mid 0.402042 -0.402042)
							(end 0.3302 -0.4318)
						)
					)
					(width 0)
					(fill yes)
				)
			)
		)
	)
	(footprint ""
		(layer "F.Cu")
		(at 116.713 -70.485 -90)
		(property "Reference" "R5312"
			(at 0 0 270)
			(layer "F.SilkS")
			(hide yes)
			(effects
				(font
					(size 1.27 1.27)
				)
			)
		)
		(property "Value" "0R2J-2-GP"
			(at 0.064008 -3.993896 270)
			(unlocked yes)
			(layer "F.Fab")
			(hide yes)
			(effects
				(font
					(size 1.016 1.016)
					(thickness 0.1524)
				)
			)
		)
		(property "Device Type" "R402H16"
			(at 0.064008 -5.517896 270)
			(unlocked yes)
			(layer "F.Fab")
			(hide yes)
			(effects
				(font
					(size 1.016 1.016)
					(thickness 0.1524)
				)
			)
		)
		(duplicate_pad_numbers_are_jumpers no)
		(fp_line
			(start -0.508 -0.9398)
			(end -0.508 0.9398)
			(stroke
				(width 0.1524)
				(type default)
			)
			(layer "F.SilkS")
		)
		(fp_line
			(start 0.508 -0.9398)
			(end -0.508 -0.9398)
			(stroke
				(width 0.1524)
				(type default)
			)
			(layer "F.SilkS")
		)
		(fp_rect
			(start -0.508 0.9398)
			(end 0.508 -0.9398)
			(stroke
				(width 0)
				(type default)
			)
			(fill no)
			(layer "F.CrtYd")
		)
		(fp_rect
			(start -0.508 0.9398)
			(end 0.508 -0.9398)
			(stroke
				(width 0)
				(type default)
			)
			(fill no)
			(layer "F.Fab")
		)
		(pad "1" smd custom
			(at 0 -0.4445 270)
			(size 0.1397 0.1397)
			(layers "F.Cu" "F.Mask" "F.Paste")
			(net "BMC_I2C_SDA_10")
			(options
				(clearance outline)
				(anchor circle)
			)
			(primitives
				(gr_poly
					(pts
						(arc
							(start -0.1778 -0.2794)
							(mid -0.249642 -0.249642)
							(end -0.2794 -0.1778)
						)
						(arc
							(start -0.2794 0.1778)
							(mid -0.249642 0.249642)
							(end -0.1778 0.2794)
						)
						(arc
							(start 0.1778 0.2794)
							(mid 0.249642 0.249642)
							(end 0.2794 0.1778)
						)
						(arc
							(start 0.2794 -0.1778)
							(mid 0.249642 -0.249642)
							(end 0.1778 -0.2794)
						)
					)
					(width 0)
					(fill yes)
				)
			)
		)
		(pad "2" smd custom
			(at 0 0.4445 270)
			(size 0.1397 0.1397)
			(layers "F.Cu" "F.Mask" "F.Paste")
			(net "TEMP_4_SDA")
			(options
				(clearance outline)
				(anchor circle)
			)
			(primitives
				(gr_poly
					(pts
						(arc
							(start -0.1778 -0.2794)
							(mid -0.249642 -0.249642)
							(end -0.2794 -0.1778)
						)
						(arc
							(start -0.2794 0.1778)
							(mid -0.249642 0.249642)
							(end -0.1778 0.2794)
						)
						(arc
							(start 0.1778 0.2794)
							(mid 0.249642 0.249642)
							(end 0.2794 0.1778)
						)
						(arc
							(start 0.2794 -0.1778)
							(mid 0.249642 -0.249642)
							(end 0.1778 -0.2794)
						)
					)
					(width 0)
					(fill yes)
				)
			)
		)
	)
	(footprint ""
		(layer "F.Cu")
		(at 197.612 -169.672 -90)
		(property "Reference" "R578"
			(at 0 0 270)
			(layer "F.SilkS")
			(hide yes)
			(effects
				(font
					(size 1.27 1.27)
				)
			)
		)
		(property "Value" "4K7R2F-GP"
			(at 0.064008 -3.993896 270)
			(unlocked yes)
			(layer "F.Fab")
			(hide yes)
			(effects
				(font
					(size 1.016 1.016)
					(thickness 0.1524)
				)
			)
		)
		(property "Device Type" "R402H16"
			(at 0.064008 -5.517896 270)
			(unlocked yes)
			(layer "F.Fab")
			(hide yes)
			(effects
				(font
					(size 1.016 1.016)
					(thickness 0.1524)
				)
			)
		)
		(duplicate_pad_numbers_are_jumpers no)
		(fp_line
			(start -0.508 -0.9398)
			(end -0.508 0.9398)
			(stroke
				(width 0.1524)
				(type default)
			)
			(layer "F.SilkS")
		)
		(fp_line
			(start 0.508 -0.9398)
			(end -0.508 -0.9398)
			(stroke
				(width 0.1524)
				(type default)
			)
			(layer "F.SilkS")
		)
		(fp_rect
			(start -0.508 0.9398)
			(end 0.508 -0.9398)
			(stroke
				(width 0)
				(type default)
			)
			(fill no)
			(layer "F.CrtYd")
		)
		(fp_rect
			(start -0.508 0.9398)
			(end 0.508 -0.9398)
			(stroke
				(width 0)
				(type default)
			)
			(fill no)
			(layer "F.Fab")
		)
		(pad "1" smd custom
			(at 0 -0.4445 270)
			(size 0.1397 0.1397)
			(layers "F.Cu" "F.Mask" "F.Paste")
			(net "P3V3_STBY")
			(options
				(clearance outline)
				(anchor circle)
			)
			(primitives
				(gr_poly
					(pts
						(arc
							(start -0.1778 -0.2794)
							(mid -0.249642 -0.249642)
							(end -0.2794 -0.1778)
						)
						(arc
							(start -0.2794 0.1778)
							(mid -0.249642 0.249642)
							(end -0.1778 0.2794)
						)
						(arc
							(start 0.1778 0.2794)
							(mid 0.249642 0.249642)
							(end 0.2794 0.1778)
						)
						(arc
							(start 0.2794 -0.1778)
							(mid 0.249642 -0.249642)
							(end 0.1778 -0.2794)
						)
					)
					(width 0)
					(fill yes)
				)
			)
		)
		(pad "2" smd custom
			(at 0 0.4445 270)
			(size 0.1397 0.1397)
			(layers "F.Cu" "F.Mask" "F.Paste")
			(net "P3V3_STBY_R1")
			(options
				(clearance outline)
				(anchor circle)
			)
			(primitives
				(gr_poly
					(pts
						(arc
							(start -0.1778 -0.2794)
							(mid -0.249642 -0.249642)
							(end -0.2794 -0.1778)
						)
						(arc
							(start -0.2794 0.1778)
							(mid -0.249642 0.249642)
							(end -0.1778 0.2794)
						)
						(arc
							(start 0.1778 0.2794)
							(mid 0.249642 0.249642)
							(end 0.2794 0.1778)
						)
						(arc
							(start 0.2794 -0.1778)
							(mid 0.249642 -0.249642)
							(end 0.1778 -0.2794)
						)
					)
					(width 0)
					(fill yes)
				)
			)
		)
	)
)
